# PolarFire SoM — KiCad custom design rules (.kicad_dru)
(version 1)
(rule "50OHM_SE_outer"
	(constraint track_width (opt 0.15mm))
	(constraint clearance (opt 0.1mm))
	(condition "(A.NetClass == '50Ohm-se')")
	(layer outer)
)

(rule "50OHM_SE_inner"
	(constraint track_width (opt 0.09mm))
	(constraint clearance (opt 0.mm))
	(condition "(A.NetClass == '50Ohm-se')")
	(layer inner)
)

#calculated as 100Ohm diff @ 55OHM SE
(rule "100OHM_diff_outer"
	(constraint track_width (opt 0.1mm))
	(constraint diff_pair_gap (opt 0.12mm))
	(constraint clearance (opt 0.1mm))
	(condition "(A.NetClass == '100Ohm-diff')")
	(layer outer)
)

(rule "100OHM_diff_inner"
	(constraint track_width (opt 0.09mm))
	(constraint diff_pair_gap (opt 0.15mm))
	(constraint clearance (opt 0.1mm))
	(condition "(A.NetClass == '100Ohm-diff')")
	(layer inner)
)

#calculated as 90Ohm diff @ 47,5OHM SE
(rule "9OHM_diff_outer"
	(constraint track_width (opt 0.11mm))
	(constraint diff_pair_gap (opt 0.09mm))
	(constraint clearance (opt 0.09mm))
	(condition "(A.NetClass == '90Ohm-diff')")
	(layer outer)
)

#calculated as 90Ohm diff @ 47,5OHM SE
(rule "90OHM_diff_inner"
	(constraint track_width (opt 0.09mm))
	(constraint diff_pair_gap (opt 0.1mm))
	(constraint clearance (opt 0.1mm))
	(condition "(A.NetClass == '90Ohm-diff')")
	(layer inner)
)

#calculated as 85Ohm diff @ 47OHM SE
(rule "85OHM_diff_outer"
	(constraint track_width (opt 0.125mm))
	(constraint diff_pair_gap (opt 0.09mm))
	(constraint clearance (opt 0.09mm))
	(condition "(A.NetClass == '85Ohm-diff_PCIe')")
	(layer outer)
)

#calculated as 85Ohm diff @ 45OHM SE
(rule "85OHM_diff_inner"
	(constraint track_width (opt 0.1mm))
	(constraint diff_pair_gap (opt 0.1mm))
	(constraint clearance (opt 0.1mm))
	(condition "(A.NetClass == '85Ohm-diff_PCIe')")
	(layer inner)
)
